# TIMECARD (Time Appliance Project (Time Card)) — schematic netlist excerpt (pin names and nets, part order shuffled) for the footprints in the layout excerpt that follows; sources: Cadence DE-HDL packaged netlist, KiCad conversion of R4006-B0001-02_R01.brd

R240  RESISTOR  150OHM 1%  pkg SMC_0402R_H016  page 15 : \1\ = OSC_125M_CLKN ; \2\ = SG
C148  CAPACITOR  0.1UF 10V 10%  pkg SMC_0402R_H022  page 14 : \1\ = XP1R0V_FPGA ; \2\ = SG

(kicad_pcb
	(version 20260206)
	(generator "pcbnew")
	(generator_version "10.0")
	(general
		(thickness 1.6)
		(legacy_teardrops no)
	)
	(paper "A4")
	(title_block
		(title "timecard-production-celestica-r4006 — R4006-B0001-02_R01.brd")
		(comment 1 "Time Appliance Project (Time Card) / footprints 296-297 of 1113")
	)
	(layers
		(0 "F.Cu" signal "TOP")
		(4 "In1.Cu" signal "L02_GND1")
		(6 "In2.Cu" signal "L03_SIG1")
		(8 "In3.Cu" signal "L04_GND2")
		(10 "In4.Cu" signal "L05_VCC1")
		(12 "In5.Cu" signal "L06_VCC2")
		(14 "In6.Cu" signal "L07_GND3")
		(16 "In7.Cu" signal "L08_SIG2")
		(18 "In8.Cu" signal "L09_GND4")
		(2 "B.Cu" signal "BOTTOM")
		(9 "F.Adhes" user "F.Adhesive")
		(11 "B.Adhes" user "B.Adhesive")
		(13 "F.Paste" user "Package Geometry/Pastemask Top")
		(15 "B.Paste" user "Package Geometry/Pastemask Bottom")
		(5 "F.SilkS" user "Ref Des/Silkscreen Top")
		(7 "B.SilkS" user "Ref Des/Silkscreen Bottom")
		(1 "F.Mask" user "Board Geometry/Soldermask Top")
		(3 "B.Mask" user "Board Geometry/Soldermask Bottom")
		(17 "Dwgs.User" user "User.Drawings")
		(19 "Cmts.User" user "User.Comments")
		(21 "Eco1.User" user "User.Eco1")
		(23 "Eco2.User" user "User.Eco2")
		(25 "Edge.Cuts" user "Board Geometry/Outline")
		(27 "Margin" user)
		(31 "F.CrtYd" user "Package Geometry/Place Bound Top")
		(29 "B.CrtYd" user "Package Geometry/Place Bound Bottom")
		(35 "F.Fab" user "Ref Des/Assembly Top")
		(33 "B.Fab" user "Ref Des/Assembly Bottom")
	)
	(footprint ""
		(layer "F.Cu")
		(at 90.805 -40.64 90)
		(property "Reference" "C148"
			(at -3.048 -0.59563 90)
			(unlocked yes)
			(layer "F.SilkS")
			(effects
				(font
					(size 0.7874 0.5842)
					(thickness 0.1524)
				)
			)
		)
		(property "Value" "VAL*"
			(at 0.0762 2.067306 90)
			(unlocked yes)
			(layer "F.Fab")
			(hide yes)
			(effects
				(font
					(size 0.7874 0.5842)
					(thickness 0.1524)
				)
			)
		)
		(property "Tolerance" "TOL*"
			(at 0.0762 3.032506 90)
			(unlocked yes)
			(layer "Cmts.User")
			(hide yes)
			(effects
				(font
					(size 0.7874 0.5842)
					(thickness 0.1524)
				)
			)
		)
		(property "User Part Number" "PARTNUM*"
			(at 0.1016 4.023106 90)
			(unlocked yes)
			(layer "Cmts.User")
			(hide yes)
			(effects
				(font
					(size 0.7874 0.5842)
					(thickness 0.1524)
				)
			)
		)
		(property "Device Type" "CAPACITOR-G105-0B104-CK,0.1UF,A"
			(at 0.0508 1.127506 90)
			(unlocked yes)
			(layer "F.Fab")
			(hide yes)
			(effects
				(font
					(size 0.7874 0.5842)
					(thickness 0.1524)
				)
			)
		)
		(duplicate_pad_numbers_are_jumpers no)
		(fp_line
			(start 1.143 -0.5588)
			(end -1.143 -0.5588)
			(stroke
				(width 0.1)
				(type default)
			)
			(layer "F.SilkS")
		)
		(fp_line
			(start -1.143 -0.5588)
			(end -1.143 0.5588)
			(stroke
				(width 0.1)
				(type default)
			)
			(layer "F.SilkS")
		)
		(fp_line
			(start 1.143 0.5588)
			(end 1.143 -0.5588)
			(stroke
				(width 0.1)
				(type default)
			)
			(layer "F.SilkS")
		)
		(fp_line
			(start -1.143 0.5588)
			(end 1.143 0.5588)
			(stroke
				(width 0.1)
				(type default)
			)
			(layer "F.SilkS")
		)
		(fp_rect
			(start -1.143 0.5588)
			(end 1.143 -0.5588)
			(stroke
				(width 0)
				(type default)
			)
			(fill no)
			(layer "F.CrtYd")
		)
		(fp_line
			(start 0.508 -0.3048)
			(end -0.508 -0.3048)
			(stroke
				(width 0.1)
				(type default)
			)
			(layer "F.Fab")
		)
		(fp_line
			(start -0.508 -0.3048)
			(end -0.508 0.3048)
			(stroke
				(width 0.1)
				(type default)
			)
			(layer "F.Fab")
		)
		(fp_line
			(start 0.508 0.3048)
			(end 0.508 -0.3048)
			(stroke
				(width 0.1)
				(type default)
			)
			(layer "F.Fab")
		)
		(fp_line
			(start -0.508 0.3048)
			(end 0.508 0.3048)
			(stroke
				(width 0.1)
				(type default)
			)
			(layer "F.Fab")
		)
		(pad "1" smd rect
			(at -0.5334 0 90)
			(size 0.7112 0.6096)
			(layers "F.Cu" "F.Mask" "F.Paste")
			(net "XP1R0V_FPGA")
		)
		(pad "2" smd rect
			(at 0.5334 0 90)
			(size 0.7112 0.6096)
			(layers "F.Cu" "F.Mask" "F.Paste")
			(net "SG")
		)
		(zone
			(layer "F.Cu")
			(hatch none 0.5)
			(connect_pads
				(clearance 0)
			)
			(min_thickness 0.25)
			(keepout
				(tracks allowed)
				(vias not_allowed)
				(pads allowed)
				(copperpour not_allowed)
				(footprints allowed)
			)
			(placement
				(enabled no)
				(sheetname "")
			)
			(fill
				(thermal_gap 0.5)
				(thermal_bridge_width 0.5)
				(island_removal_mode 0)
			)
			(polygon
				(pts
					(xy 91.1098 -40.5638) (xy 91.1098 -40.7162) (xy 90.5002 -40.7162) (xy 90.5002 -40.5638)
				)
			)
		)
	)
	(footprint ""
		(layer "F.Cu")
		(at 101.219 -24.638 180)
		(property "Reference" "R240"
			(at 10.795 -0.16637 0)
			(unlocked yes)
			(layer "F.SilkS")
			(effects
				(font
					(size 0.7874 0.5842)
					(thickness 0.1524)
				)
			)
		)
		(property "Value" "VAL*"
			(at 0.02032 2.13233 180)
			(unlocked yes)
			(layer "F.Fab")
			(hide yes)
			(effects
				(font
					(size 0.7874 0.5842)
					(thickness 0.1524)
				)
			)
		)
		(property "Tolerance" "TOL*"
			(at 0.044704 3.05435 180)
			(unlocked yes)
			(layer "Cmts.User")
			(hide yes)
			(effects
				(font
					(size 0.7874 0.5842)
					(thickness 0.1524)
				)
			)
		)
		(property "User Part Number" "PARTNUM*"
			(at 0.02032 4.024884 180)
			(unlocked yes)
			(layer "Cmts.User")
			(hide yes)
			(effects
				(font
					(size 0.7874 0.5842)
					(thickness 0.1524)
				)
			)
		)
		(property "Device Type" "RESISTOR-G155-11500-01,150OHM,A"
			(at 0.008382 1.210564 180)
			(unlocked yes)
			(layer "F.Fab")
			(hide yes)
			(effects
				(font
					(size 0.7874 0.5842)
					(thickness 0.1524)
				)
			)
		)
		(duplicate_pad_numbers_are_jumpers no)
		(fp_line
			(start 1.143 0.5588)
			(end 1.143 -0.5588)
			(stroke
				(width 0.1)
				(type default)
			)
			(layer "F.SilkS")
		)
		(fp_line
			(start 1.143 -0.5588)
			(end -1.143 -0.5588)
			(stroke
				(width 0.1)
				(type default)
			)
			(layer "F.SilkS")
		)
		(fp_line
			(start -1.143 0.5588)
			(end 1.143 0.5588)
			(stroke
				(width 0.1)
				(type default)
			)
			(layer "F.SilkS")
		)
		(fp_line
			(start -1.143 -0.5588)
			(end -1.143 0.5588)
			(stroke
				(width 0.1)
				(type default)
			)
			(layer "F.SilkS")
		)
		(fp_rect
			(start 1.143 -0.5588)
			(end -1.143 0.5588)
			(stroke
				(width 0)
				(type default)
			)
			(fill no)
			(layer "F.CrtYd")
		)
		(fp_line
			(start 0.508 0.3048)
			(end 0.508 -0.3048)
			(stroke
				(width 0.1)
				(type default)
			)
			(layer "F.Fab")
		)
		(fp_line
			(start 0.508 -0.3048)
			(end -0.508 -0.3048)
			(stroke
				(width 0.1)
				(type default)
			)
			(layer "F.Fab")
		)
		(fp_line
			(start -0.508 0.3048)
			(end 0.508 0.3048)
			(stroke
				(width 0.1)
				(type default)
			)
			(layer "F.Fab")
		)
		(fp_line
			(start -0.508 -0.3048)
			(end -0.508 0.3048)
			(stroke
				(width 0.1)
				(type default)
			)
			(layer "F.Fab")
		)
		(pad "1" smd rect
			(at -0.5334 0 180)
			(size 0.7112 0.6096)
			(layers "F.Cu" "F.Mask" "F.Paste")
			(net "OSC_125M_CLKN")
		)
		(pad "2" smd rect
			(at 0.5334 0 180)
			(size 0.7112 0.6096)
			(layers "F.Cu" "F.Mask" "F.Paste")
			(net "SG")
		)
		(zone
			(layer "F.Cu")
			(hatch none 0.5)
			(connect_pads
				(clearance 0)
			)
			(min_thickness 0.25)
			(keepout
				(tracks allowed)
				(vias not_allowed)
				(pads allowed)
				(copperpour not_allowed)
				(footprints allowed)
			)
			(placement
				(enabled no)
				(sheetname "")
			)
			(fill
				(thermal_gap 0.5)
				(thermal_bridge_width 0.5)
				(island_removal_mode 0)
			)
			(polygon
				(pts
					(xy 101.1428 -24.3332) (xy 101.2952 -24.3332) (xy 101.2952 -24.9428) (xy 101.1428 -24.9428)
				)
			)
		)
	)
)
